# T6G (Grand Teton) — schematic netlist excerpt (pin names and nets, part order shuffled) for the footprints in the layout excerpt that follows; sources: Cadence DE-HDL packaged netlist, KiCad conversion of 04192023_DAF0TMB3IC0_F0TG_MB_C_brd_V02_OCP.brd

PR350  Q_RES  0 5% CHIP  pkg 0402LF  page 195 : A = PVDDCR_CPU0_P0_VOS3 ; B = PVDDCR_CPU0_P0
C544  Q_CAP  0.1UF 10V 10% X7S  pkg C0201  page 279 : A = P0V9_CPU0_RT0_2A_2D ; B = GND
C7012  Q_CAPP  470UF 2.5V 20% SPCAP  pkg SMLF  page 290 : A = P0V9_CPU0_RT1_2A ; B = GND

(kicad_pcb
	(version 20260206)
	(generator "pcbnew")
	(generator_version "10.0")
	(general
		(thickness 1.6)
		(legacy_teardrops no)
	)
	(paper "A4")
	(title_block
		(title "04192023_DAF0TMB3IC0_F0TG_MB_C_brd_V02_OCP.brd")
		(comment 1 "Grand Teton / footprints 6353-6355 of 8354")
	)
	(layers
		(0 "F.Cu" signal "TOP")
		(4 "In1.Cu" signal "GND")
		(6 "In2.Cu" signal "IN1")
		(8 "In3.Cu" signal "GND1")
		(10 "In4.Cu" signal "IN2")
		(12 "In5.Cu" signal "GND2")
		(14 "In6.Cu" signal "IN3")
		(16 "In7.Cu" signal "GND3")
		(18 "In8.Cu" signal "VCC")
		(20 "In9.Cu" signal "VCC1")
		(22 "In10.Cu" signal "GND4")
		(24 "In11.Cu" signal "IN4")
		(26 "In12.Cu" signal "GND5")
		(28 "In13.Cu" signal "IN5")
		(30 "In14.Cu" signal "GND6")
		(32 "In15.Cu" signal "IN6")
		(34 "In16.Cu" signal "GND7")
		(2 "B.Cu" signal "BOTTOM")
		(9 "F.Adhes" user "F.Adhesive")
		(11 "B.Adhes" user "B.Adhesive")
		(13 "F.Paste" user "Package Geometry/Pastemask Top")
		(15 "B.Paste" user "Package Geometry/Pastemask Bottom")
		(5 "F.SilkS" user "Ref Des/Silkscreen Top")
		(7 "B.SilkS" user "Ref Des/Silkscreen Bottom")
		(1 "F.Mask" user "Board Geometry/Soldermask Top")
		(3 "B.Mask" user "Board Geometry/Soldermask Bottom")
		(17 "Dwgs.User" user "User.Drawings")
		(19 "Cmts.User" user "User.Comments")
		(21 "Eco1.User" user "User.Eco1")
		(23 "Eco2.User" user "User.Eco2")
		(25 "Edge.Cuts" user "Board Geometry/Outline")
		(27 "Margin" user)
		(31 "F.CrtYd" user "Package Geometry/Place Bound Top")
		(29 "B.CrtYd" user "Package Geometry/Place Bound Bottom")
		(35 "F.Fab" user "Ref Des/Assembly Top")
		(33 "B.Fab" user "Ref Des/Assembly Bottom")
	)
	(footprint ""
		(layer "B.Cu")
		(at 316.718188 -396.393162 -90)
		(property "Reference" "C544"
			(at 0 0 90)
			(layer "B.SilkS")
			(hide yes)
			(effects
				(font
					(size 1.27 1.27)
				)
				(justify mirror)
			)
		)
		(property "Value" ""
			(at 0 0 90)
			(layer "B.Fab")
			(effects
				(font
					(size 1.27 1.27)
				)
				(justify mirror)
			)
		)
		(duplicate_pad_numbers_are_jumpers no)
		(fp_line
			(start -0.299974 0.150114)
			(end 0.299974 0.150114)
			(stroke
				(width 0.1)
				(type default)
			)
			(layer "B.Fab")
		)
		(fp_line
			(start 0.299974 0.150114)
			(end 0.299974 -0.150114)
			(stroke
				(width 0.1)
				(type default)
			)
			(layer "B.Fab")
		)
		(fp_line
			(start -0.299974 -0.150114)
			(end -0.299974 0.150114)
			(stroke
				(width 0.1)
				(type default)
			)
			(layer "B.Fab")
		)
		(fp_line
			(start 0.299974 -0.150114)
			(end -0.299974 -0.150114)
			(stroke
				(width 0.1)
				(type default)
			)
			(layer "B.Fab")
		)
		(pad "1" smd rect
			(at 0.2667 0 90)
			(size 0.3048 0.381)
			(layers "B.Cu" "B.Mask" "B.Paste")
			(net "P0V9_CPU0_RT0_2A_2D")
		)
		(pad "2" smd rect
			(at -0.2667 0 90)
			(size 0.3048 0.381)
			(layers "B.Cu" "B.Mask" "B.Paste")
			(net "GND")
		)
	)
	(footprint ""
		(layer "B.Cu")
		(at 384.739388 -180.078634 90)
		(property "Reference" "PR350"
			(at 0 0 90)
			(layer "B.SilkS")
			(hide yes)
			(effects
				(font
					(size 1.27 1.27)
				)
				(justify mirror)
			)
		)
		(property "Value" ""
			(at 0 0 90)
			(layer "B.Fab")
			(effects
				(font
					(size 1.27 1.27)
				)
				(justify mirror)
			)
		)
		(duplicate_pad_numbers_are_jumpers no)
		(fp_line
			(start 0.7874 -0.4064)
			(end -0.7874 -0.4064)
			(stroke
				(width 0.1524)
				(type default)
			)
			(layer "B.SilkS")
		)
		(fp_line
			(start -0.7874 -0.4064)
			(end -0.7874 0.4064)
			(stroke
				(width 0.1524)
				(type default)
			)
			(layer "B.SilkS")
		)
		(fp_line
			(start 0.7874 0.4064)
			(end 0.7874 -0.4064)
			(stroke
				(width 0.1524)
				(type default)
			)
			(layer "B.SilkS")
		)
		(fp_line
			(start -0.7874 0.4064)
			(end 0.7874 0.4064)
			(stroke
				(width 0.1524)
				(type default)
			)
			(layer "B.SilkS")
		)
		(fp_line
			(start 0.67945 -0.305054)
			(end 0.12065 -0.305054)
			(stroke
				(width 0.1)
				(type default)
			)
			(layer "B.Fab")
		)
		(fp_line
			(start 0.12065 -0.305054)
			(end 0.12065 -0.2794)
			(stroke
				(width 0.1)
				(type default)
			)
			(layer "B.Fab")
		)
		(fp_line
			(start -0.12065 -0.3048)
			(end -0.67945 -0.3048)
			(stroke
				(width 0.1)
				(type default)
			)
			(layer "B.Fab")
		)
		(fp_line
			(start -0.67945 -0.3048)
			(end -0.67945 0.3048)
			(stroke
				(width 0.1)
				(type default)
			)
			(layer "B.Fab")
		)
		(fp_line
			(start 0.12065 -0.2794)
			(end -0.12065 -0.2794)
			(stroke
				(width 0.1)
				(type default)
			)
			(layer "B.Fab")
		)
		(fp_line
			(start -0.12065 -0.2794)
			(end -0.12065 -0.3048)
			(stroke
				(width 0.1)
				(type default)
			)
			(layer "B.Fab")
		)
		(fp_line
			(start 0.12065 0.2794)
			(end 0.12065 0.3048)
			(stroke
				(width 0.1)
				(type default)
			)
			(layer "B.Fab")
		)
		(fp_line
			(start -0.120396 0.2794)
			(end 0.12065 0.2794)
			(stroke
				(width 0.1)
				(type default)
			)
			(layer "B.Fab")
		)
		(fp_line
			(start 0.67945 0.3048)
			(end 0.67945 -0.305054)
			(stroke
				(width 0.1)
				(type default)
			)
			(layer "B.Fab")
		)
		(fp_line
			(start 0.12065 0.3048)
			(end 0.67945 0.3048)
			(stroke
				(width 0.1)
				(type default)
			)
			(layer "B.Fab")
		)
		(fp_line
			(start -0.120396 0.3048)
			(end -0.120396 0.2794)
			(stroke
				(width 0.1)
				(type default)
			)
			(layer "B.Fab")
		)
		(fp_line
			(start -0.67945 0.3048)
			(end -0.120396 0.3048)
			(stroke
				(width 0.1)
				(type default)
			)
			(layer "B.Fab")
		)
		(pad "1" smd circle
			(at 0.40005 0 270)
			(size 0 0)
			(layers "B.Cu" "B.Mask" "B.Paste")
			(net "PVDDCR_CPU0_P0_VOS3")
		)
		(pad "2" smd circle
			(at -0.40005 0 270)
			(size 0 0)
			(layers "B.Cu" "B.Mask" "B.Paste")
			(net "PVDDCR_CPU0_P0")
		)
	)
	(footprint ""
		(layer "B.Cu")
		(at 350.495362 -389.49503)
		(property "Reference" "C7012"
			(at 2.35966 3.083052 0)
			(unlocked yes)
			(layer "B.SilkS")
			(effects
				(font
					(size 0.7874 0.5842)
					(thickness 0.1524)
				)
				(justify left mirror)
			)
		)
		(property "Value" ""
			(at 0 0 0)
			(layer "B.Fab")
			(effects
				(font
					(size 1.27 1.27)
				)
				(justify mirror)
			)
		)
		(duplicate_pad_numbers_are_jumpers no)
		(fp_line
			(start -4.53898 -2.15011)
			(end -4.53898 2.15011)
			(stroke
				(width 0.1524)
				(type default)
			)
			(layer "B.SilkS")
		)
		(fp_line
			(start -4.53898 2.15011)
			(end 4.53898 2.15011)
			(stroke
				(width 0.1524)
				(type default)
			)
			(layer "B.SilkS")
		)
		(fp_line
			(start 4.53898 -2.150618)
			(end 4.539742 2.152142)
			(stroke
				(width 0.1524)
				(type default)
			)
			(layer "B.SilkS")
		)
		(fp_line
			(start 4.53898 -2.15011)
			(end -4.53898 -2.15011)
			(stroke
				(width 0.1524)
				(type default)
			)
			(layer "B.SilkS")
		)
		(fp_line
			(start 4.53898 2.15011)
			(end 4.53898 -2.15011)
			(stroke
				(width 0.1524)
				(type default)
			)
			(layer "B.SilkS")
		)
		(fp_line
			(start 4.69138 -2.150618)
			(end 4.692396 2.161032)
			(stroke
				(width 0.1524)
				(type default)
			)
			(layer "B.SilkS")
		)
		(fp_line
			(start 4.83108 2.150364)
			(end 4.447794 2.149348)
			(stroke
				(width 0.1524)
				(type default)
			)
			(layer "B.SilkS")
		)
		(fp_line
			(start 4.84378 -2.150618)
			(end 4.53898 -2.150618)
			(stroke
				(width 0.1524)
				(type default)
			)
			(layer "B.SilkS")
		)
		(fp_line
			(start 4.84378 -2.150618)
			(end 4.842256 2.163064)
			(stroke
				(width 0.1524)
				(type default)
			)
			(layer "B.SilkS")
		)
		(fp_line
			(start -3.64998 -2.15011)
			(end -3.64998 2.15011)
			(stroke
				(width 0.1)
				(type default)
			)
			(layer "B.Fab")
		)
		(fp_line
			(start -3.64998 2.15011)
			(end 3.64998 2.15011)
			(stroke
				(width 0.1)
				(type default)
			)
			(layer "B.Fab")
		)
		(fp_line
			(start 3.64998 -2.15011)
			(end -3.64998 -2.15011)
			(stroke
				(width 0.1)
				(type default)
			)
			(layer "B.Fab")
		)
		(fp_line
			(start 3.64998 2.15011)
			(end 3.64998 -2.15011)
			(stroke
				(width 0.1)
				(type default)
			)
			(layer "B.Fab")
		)
		(fp_text user "-"
			(at -2.872994 2.336292 0)
			(unlocked yes)
			(layer "B.SilkS")
			(effects
				(font
					(size 1.905 1.4224)
					(thickness 0.1524)
				)
				(justify left mirror)
			)
		)
		(fp_text user "+"
			(at 6.214872 -0.337058 0)
			(unlocked yes)
			(layer "B.SilkS")
			(effects
				(font
					(size 1.905 1.4224)
					(thickness 0.1524)
				)
				(justify left mirror)
			)
		)
		(fp_text user "-"
			(at -4.313174 -0.094488 0)
			(unlocked yes)
			(layer "B.Fab")
			(effects
				(font
					(size 1.905 1.4224)
					(thickness 0.1524)
				)
				(justify left mirror)
			)
		)
		(fp_text user "+"
			(at 6.214872 -0.337058 0)
			(unlocked yes)
			(layer "B.Fab")
			(effects
				(font
					(size 1.905 1.4224)
					(thickness 0.1524)
				)
				(justify left mirror)
			)
		)
		(pad "1" smd rect
			(at 3.199892 0 180)
			(size 2.413 2.8194)
			(layers "B.Cu" "B.Mask" "B.Paste")
			(net "P0V9_CPU0_RT1_2A")
		)
		(pad "2" smd rect
			(at -3.199892 0 180)
			(size 2.413 2.8194)
			(layers "B.Cu" "B.Mask" "B.Paste")
			(net "GND")
		)
	)
)
